# TIMECARD (Time Appliance Project (Time Card)) — schematic netlist excerpt (pin names and nets, part order shuffled) for the footprints in the layout excerpt that follows; sources: Cadence DE-HDL packaged netlist, KiCad conversion of R4006-B0001-02_R01.brd

R52  RESISTOR  5.1KOHM 1%  pkg SMC_0402R_H016  page 28 : \1\ = XP3R3V_EN ; \2\ = SG
C6  CAPACITOR  10UF 25V 20%  pkg SMC_0805R_H057  page 27 : \1\ = XP12R0V_A_AVIN ; \2\ = SG
TP52  TP_PIONT  pkg TP010CT020B030_PTH  page 25 : \1\ = XP12R0V

(kicad_pcb
	(version 20260206)
	(generator "pcbnew")
	(generator_version "10.0")
	(general
		(thickness 1.6)
		(legacy_teardrops no)
	)
	(paper "A4")
	(title_block
		(title "timecard-production-celestica-r4006 — R4006-B0001-02_R01.brd")
		(comment 1 "Time Appliance Project (Time Card) / footprints 453-456 of 1113")
	)
	(layers
		(0 "F.Cu" signal "TOP")
		(4 "In1.Cu" signal "L02_GND1")
		(6 "In2.Cu" signal "L03_SIG1")
		(8 "In3.Cu" signal "L04_GND2")
		(10 "In4.Cu" signal "L05_VCC1")
		(12 "In5.Cu" signal "L06_VCC2")
		(14 "In6.Cu" signal "L07_GND3")
		(16 "In7.Cu" signal "L08_SIG2")
		(18 "In8.Cu" signal "L09_GND4")
		(2 "B.Cu" signal "BOTTOM")
		(9 "F.Adhes" user "F.Adhesive")
		(11 "B.Adhes" user "B.Adhesive")
		(13 "F.Paste" user "Package Geometry/Pastemask Top")
		(15 "B.Paste" user "Package Geometry/Pastemask Bottom")
		(5 "F.SilkS" user "Ref Des/Silkscreen Top")
		(7 "B.SilkS" user "Ref Des/Silkscreen Bottom")
		(1 "F.Mask" user "Board Geometry/Soldermask Top")
		(3 "B.Mask" user "Board Geometry/Soldermask Bottom")
		(17 "Dwgs.User" user "User.Drawings")
		(19 "Cmts.User" user "User.Comments")
		(21 "Eco1.User" user "User.Eco1")
		(23 "Eco2.User" user "User.Eco2")
		(25 "Edge.Cuts" user "Board Geometry/Outline")
		(27 "Margin" user)
		(31 "F.CrtYd" user "Package Geometry/Place Bound Top")
		(29 "B.CrtYd" user "Package Geometry/Place Bound Bottom")
		(35 "F.Fab" user "Ref Des/Assembly Top")
		(33 "B.Fab" user "Ref Des/Assembly Bottom")
	)
	(footprint ""
		(layer "F.Cu")
		(at 135.4074 -97.2058 180)
		(property "Reference" "C6"
			(at 2.286 -0.42037 0)
			(unlocked yes)
			(layer "F.SilkS")
			(effects
				(font
					(size 0.7874 0.5842)
					(thickness 0.1524)
				)
			)
		)
		(property "Value" "VAL*"
			(at 0.0762 3.134106 180)
			(unlocked yes)
			(layer "F.Fab")
			(hide yes)
			(effects
				(font
					(size 0.7874 0.5842)
					(thickness 0.1524)
				)
			)
		)
		(property "Device Type" "CAPACITOR-G107-0F106-EM,10UF,2A"
			(at 0.0508 2.194306 180)
			(unlocked yes)
			(layer "F.Fab")
			(hide yes)
			(effects
				(font
					(size 0.7874 0.5842)
					(thickness 0.1524)
				)
			)
		)
		(property "User Part Number" "PARTNUM*"
			(at 0.1016 5.013706 180)
			(unlocked yes)
			(layer "Cmts.User")
			(hide yes)
			(effects
				(font
					(size 0.7874 0.5842)
					(thickness 0.1524)
				)
			)
		)
		(property "Tolerance" "TOL*"
			(at 0.0762 4.048506 180)
			(unlocked yes)
			(layer "Cmts.User")
			(hide yes)
			(effects
				(font
					(size 0.7874 0.5842)
					(thickness 0.1524)
				)
			)
		)
		(duplicate_pad_numbers_are_jumpers no)
		(fp_line
			(start 1.5748 0.9398)
			(end 1.5748 -0.9398)
			(stroke
				(width 0.1)
				(type default)
			)
			(layer "F.SilkS")
		)
		(fp_line
			(start 1.5748 -0.9398)
			(end -1.5748 -0.9398)
			(stroke
				(width 0.1)
				(type default)
			)
			(layer "F.SilkS")
		)
		(fp_line
			(start -1.5748 0.9398)
			(end 1.5748 0.9398)
			(stroke
				(width 0.1)
				(type default)
			)
			(layer "F.SilkS")
		)
		(fp_line
			(start -1.5748 -0.9398)
			(end -1.5748 0.9398)
			(stroke
				(width 0.1)
				(type default)
			)
			(layer "F.SilkS")
		)
		(fp_rect
			(start 1.5748 -0.9398)
			(end -1.5748 0.9398)
			(stroke
				(width 0)
				(type default)
			)
			(fill no)
			(layer "F.CrtYd")
		)
		(fp_line
			(start 1.016 0.635)
			(end 1.016 -0.635)
			(stroke
				(width 0.1)
				(type default)
			)
			(layer "F.Fab")
		)
		(fp_line
			(start 1.016 -0.635)
			(end -1.016 -0.635)
			(stroke
				(width 0.1)
				(type default)
			)
			(layer "F.Fab")
		)
		(fp_line
			(start -1.016 0.635)
			(end 1.016 0.635)
			(stroke
				(width 0.1)
				(type default)
			)
			(layer "F.Fab")
		)
		(fp_line
			(start -1.016 -0.635)
			(end -1.016 0.635)
			(stroke
				(width 0.1)
				(type default)
			)
			(layer "F.Fab")
		)
		(pad "1" smd rect
			(at -0.8382 0 180)
			(size 0.9652 1.3716)
			(layers "F.Cu" "F.Mask" "F.Paste")
			(net "XP12R0V_A_AVIN")
		)
		(pad "2" smd rect
			(at 0.8382 0 180)
			(size 0.9652 1.3716)
			(layers "F.Cu" "F.Mask" "F.Paste")
			(net "SG")
		)
		(zone
			(layer "F.Cu")
			(hatch none 0.5)
			(connect_pads
				(clearance 0)
			)
			(min_thickness 0.25)
			(keepout
				(tracks allowed)
				(vias not_allowed)
				(pads allowed)
				(copperpour not_allowed)
				(footprints allowed)
			)
			(placement
				(enabled no)
				(sheetname "")
			)
			(fill
				(thermal_gap 0.5)
				(thermal_bridge_width 0.5)
				(island_removal_mode 0)
			)
			(polygon
				(pts
					(xy 135.1788 -96.5708) (xy 135.636 -96.5708) (xy 135.636 -97.8408) (xy 135.1788 -97.8408)
				)
			)
		)
	)
	(footprint ""
		(layer "F.Cu")
		(at 137.3124 -59.5884 180)
		(property "Reference" "TP52"
			(at 3.5306 0.06223 0)
			(unlocked yes)
			(layer "F.SilkS")
			(effects
				(font
					(size 0.7874 0.5842)
					(thickness 0.1524)
				)
				(justify left)
			)
		)
		(property "Value" ""
			(at 0 0 180)
			(layer "F.Fab")
			(effects
				(font
					(size 1.27 1.27)
				)
			)
		)
		(property "Device Type" "TP_PIONT-TP010CT020B030_PTH-TPA"
			(at -1.341882 0.996696 180)
			(unlocked yes)
			(layer "F.Fab")
			(hide yes)
			(effects
				(font
					(size 0.7874 0.5842)
					(thickness 0.1524)
				)
				(justify left)
			)
		)
		(duplicate_pad_numbers_are_jumpers no)
		(fp_poly
			(pts
				(arc
					(start -0.889 0)
					(mid 0.889 0)
					(end -0.889 0)
				)
			)
			(stroke
				(width 0)
				(type default)
			)
			(fill no)
			(layer "B.CrtYd")
		)
		(fp_poly
			(pts
				(arc
					(start -0.889 0)
					(mid 0.889 0)
					(end -0.889 0)
				)
			)
			(stroke
				(width 0)
				(type default)
			)
			(fill no)
			(layer "F.CrtYd")
		)
		(pad "1" thru_hole circle
			(at 0 0 180)
			(size 0.508 0.508)
			(drill 0.254)
			(layers "*.Cu" "*.Mask")
			(remove_unused_layers no)
			(net "XP12R0V")
			(clearance 0.1016)
			(padstack
				(mode front_inner_back)
				(layer "Inner"
					(shape circle)
					(size 0.508 0.508)
					(clearance 0.1016)
				)
				(layer "B.Cu"
					(shape circle)
					(size 0.762 0.762)
					(clearance -0.0254)
				)
			)
		)
	)
	(footprint ""
		(layer "F.Cu")
		(at 38.1 -127.254)
		(property "Reference" "SP74"
			(at 0 0 0)
			(layer "F.SilkS")
			(hide yes)
			(effects
				(font
					(size 1.27 1.27)
				)
			)
		)
		(property "Value" ""
			(at 0 0 0)
			(layer "F.Fab")
			(effects
				(font
					(size 1.27 1.27)
				)
			)
		)
		(duplicate_pad_numbers_are_jumpers no)
	)
	(footprint ""
		(layer "F.Cu")
		(at 89.9922 -103.5558)
		(property "Reference" "R52"
			(at 3.048 0.29337 0)
			(unlocked yes)
			(layer "F.SilkS")
			(effects
				(font
					(size 0.7874 0.5842)
					(thickness 0.1524)
				)
			)
		)
		(property "Value" "VAL*"
			(at 0.02032 2.13233 0)
			(unlocked yes)
			(layer "F.Fab")
			(hide yes)
			(effects
				(font
					(size 0.7874 0.5842)
					(thickness 0.1524)
				)
			)
		)
		(property "Tolerance" "TOL*"
			(at 0.044704 3.05435 0)
			(unlocked yes)
			(layer "Cmts.User")
			(hide yes)
			(effects
				(font
					(size 0.7874 0.5842)
					(thickness 0.1524)
				)
			)
		)
		(property "User Part Number" "PARTNUM*"
			(at 0.02032 4.024884 0)
			(unlocked yes)
			(layer "Cmts.User")
			(hide yes)
			(effects
				(font
					(size 0.7874 0.5842)
					(thickness 0.1524)
				)
			)
		)
		(property "Device Type" "RESISTOR-G155-05101-01,5.1KOHMA"
			(at 0.008382 1.210564 0)
			(unlocked yes)
			(layer "F.Fab")
			(hide yes)
			(effects
				(font
					(size 0.7874 0.5842)
					(thickness 0.1524)
				)
			)
		)
		(duplicate_pad_numbers_are_jumpers no)
		(fp_line
			(start -1.143 -0.5588)
			(end -1.143 0.5588)
			(stroke
				(width 0.1)
				(type default)
			)
			(layer "F.SilkS")
		)
		(fp_line
			(start -1.143 0.5588)
			(end 1.143 0.5588)
			(stroke
				(width 0.1)
				(type default)
			)
			(layer "F.SilkS")
		)
		(fp_line
			(start 1.143 -0.5588)
			(end -1.143 -0.5588)
			(stroke
				(width 0.1)
				(type default)
			)
			(layer "F.SilkS")
		)
		(fp_line
			(start 1.143 0.5588)
			(end 1.143 -0.5588)
			(stroke
				(width 0.1)
				(type default)
			)
			(layer "F.SilkS")
		)
		(fp_rect
			(start -1.143 0.5588)
			(end 1.143 -0.5588)
			(stroke
				(width 0)
				(type default)
			)
			(fill no)
			(layer "F.CrtYd")
		)
		(fp_line
			(start -0.508 -0.3048)
			(end -0.508 0.3048)
			(stroke
				(width 0.1)
				(type default)
			)
			(layer "F.Fab")
		)
		(fp_line
			(start -0.508 0.3048)
			(end 0.508 0.3048)
			(stroke
				(width 0.1)
				(type default)
			)
			(layer "F.Fab")
		)
		(fp_line
			(start 0.508 -0.3048)
			(end -0.508 -0.3048)
			(stroke
				(width 0.1)
				(type default)
			)
			(layer "F.Fab")
		)
		(fp_line
			(start 0.508 0.3048)
			(end 0.508 -0.3048)
			(stroke
				(width 0.1)
				(type default)
			)
			(layer "F.Fab")
		)
		(pad "1" smd rect
			(at -0.5334 0)
			(size 0.7112 0.6096)
			(layers "F.Cu" "F.Mask" "F.Paste")
			(net "XP3R3V_EN")
		)
		(pad "2" smd rect
			(at 0.5334 0)
			(size 0.7112 0.6096)
			(layers "F.Cu" "F.Mask" "F.Paste")
			(net "SG")
		)
		(zone
			(layer "F.Cu")
			(hatch none 0.5)
			(connect_pads
				(clearance 0)
			)
			(min_thickness 0.25)
			(keepout
				(tracks allowed)
				(vias not_allowed)
				(pads allowed)
				(copperpour not_allowed)
				(footprints allowed)
			)
			(placement
				(enabled no)
				(sheetname "")
			)
			(fill
				(thermal_gap 0.5)
				(thermal_bridge_width 0.5)
				(island_removal_mode 0)
			)
			(polygon
				(pts
					(xy 89.916 -103.251) (xy 90.0684 -103.251) (xy 90.0684 -103.8606) (xy 89.916 -103.8606)
				)
			)
		)
	)
)
